# T6G (Grand Teton) — schematic netlist excerpt (pin names and nets, part order shuffled) for the footprints in the layout excerpt that follows; sources: Cadence DE-HDL packaged netlist, KiCad conversion of 04192023_DAF0TMB3IC0_F0TG_MB_C_brd_V02_OCP.brd

R3452  Q_RES  100K 1% CHIP  pkg 0402LF  page 128 : A = GPU_BASE_STBY_EN ; B = GND
C6591  Q_CAP_DIFFBUS  DIFF BUS_0.22UF 6.3V 20% X6S  pkg C0201  page 297 : \1\ = P5E_CPU0_P2_TX_BUF_C_DP<13> ; \2\ = P5E_CPU0_P2_TX_BUF_DP<13>
R997  Q_RES  4.7K 5% CHIP  pkg 0201LF  page 276 : A = JTAG_TEST_MODE_RT_CPU0_P0 ; B = GND

(kicad_pcb
	(version 20260206)
	(generator "pcbnew")
	(generator_version "10.0")
	(general
		(thickness 1.6)
		(legacy_teardrops no)
	)
	(paper "A4")
	(title_block
		(title "04192023_DAF0TMB3IC0_F0TG_MB_C_brd_V02_OCP.brd")
		(comment 1 "Grand Teton / footprints 4880-4882 of 8354")
	)
	(layers
		(0 "F.Cu" signal "TOP")
		(4 "In1.Cu" signal "GND")
		(6 "In2.Cu" signal "IN1")
		(8 "In3.Cu" signal "GND1")
		(10 "In4.Cu" signal "IN2")
		(12 "In5.Cu" signal "GND2")
		(14 "In6.Cu" signal "IN3")
		(16 "In7.Cu" signal "GND3")
		(18 "In8.Cu" signal "VCC")
		(20 "In9.Cu" signal "VCC1")
		(22 "In10.Cu" signal "GND4")
		(24 "In11.Cu" signal "IN4")
		(26 "In12.Cu" signal "GND5")
		(28 "In13.Cu" signal "IN5")
		(30 "In14.Cu" signal "GND6")
		(32 "In15.Cu" signal "IN6")
		(34 "In16.Cu" signal "GND7")
		(2 "B.Cu" signal "BOTTOM")
		(9 "F.Adhes" user "F.Adhesive")
		(11 "B.Adhes" user "B.Adhesive")
		(13 "F.Paste" user "Package Geometry/Pastemask Top")
		(15 "B.Paste" user "Package Geometry/Pastemask Bottom")
		(5 "F.SilkS" user "Ref Des/Silkscreen Top")
		(7 "B.SilkS" user "Ref Des/Silkscreen Bottom")
		(1 "F.Mask" user "Board Geometry/Soldermask Top")
		(3 "B.Mask" user "Board Geometry/Soldermask Bottom")
		(17 "Dwgs.User" user "User.Drawings")
		(19 "Cmts.User" user "User.Comments")
		(21 "Eco1.User" user "User.Eco1")
		(23 "Eco2.User" user "User.Eco2")
		(25 "Edge.Cuts" user "Board Geometry/Outline")
		(27 "Margin" user)
		(31 "F.CrtYd" user "Package Geometry/Place Bound Top")
		(29 "B.CrtYd" user "Package Geometry/Place Bound Bottom")
		(35 "F.Fab" user "Ref Des/Assembly Top")
		(33 "B.Fab" user "Ref Des/Assembly Bottom")
	)
	(footprint ""
		(layer "F.Cu")
		(at 118.618 -432.054 180)
		(property "Reference" "R3452"
			(at 0 0 180)
			(layer "F.SilkS")
			(hide yes)
			(effects
				(font
					(size 1.27 1.27)
				)
			)
		)
		(property "Value" ""
			(at 0 0 180)
			(layer "F.Fab")
			(effects
				(font
					(size 1.27 1.27)
				)
			)
		)
		(duplicate_pad_numbers_are_jumpers no)
		(fp_line
			(start 0.7874 0.4064)
			(end -0.7874 0.4064)
			(stroke
				(width 0.1524)
				(type default)
			)
			(layer "F.SilkS")
		)
		(fp_line
			(start 0.7874 -0.4064)
			(end 0.7874 0.4064)
			(stroke
				(width 0.1524)
				(type default)
			)
			(layer "F.SilkS")
		)
		(fp_line
			(start -0.7874 0.4064)
			(end -0.7874 -0.4064)
			(stroke
				(width 0.1524)
				(type default)
			)
			(layer "F.SilkS")
		)
		(fp_line
			(start -0.7874 -0.4064)
			(end 0.7874 -0.4064)
			(stroke
				(width 0.1524)
				(type default)
			)
			(layer "F.SilkS")
		)
		(fp_line
			(start 0.67945 0.3048)
			(end 0.120396 0.3048)
			(stroke
				(width 0.1)
				(type default)
			)
			(layer "F.Fab")
		)
		(fp_line
			(start 0.67945 -0.3048)
			(end 0.67945 0.3048)
			(stroke
				(width 0.1)
				(type default)
			)
			(layer "F.Fab")
		)
		(fp_line
			(start 0.12065 -0.2794)
			(end 0.12065 -0.3048)
			(stroke
				(width 0.1)
				(type default)
			)
			(layer "F.Fab")
		)
		(fp_line
			(start 0.12065 -0.3048)
			(end 0.67945 -0.3048)
			(stroke
				(width 0.1)
				(type default)
			)
			(layer "F.Fab")
		)
		(fp_line
			(start 0.120396 0.3048)
			(end 0.120396 0.2794)
			(stroke
				(width 0.1)
				(type default)
			)
			(layer "F.Fab")
		)
		(fp_line
			(start 0.120396 0.2794)
			(end -0.12065 0.2794)
			(stroke
				(width 0.1)
				(type default)
			)
			(layer "F.Fab")
		)
		(fp_line
			(start -0.12065 0.3048)
			(end -0.67945 0.3048)
			(stroke
				(width 0.1)
				(type default)
			)
			(layer "F.Fab")
		)
		(fp_line
			(start -0.12065 0.2794)
			(end -0.12065 0.3048)
			(stroke
				(width 0.1)
				(type default)
			)
			(layer "F.Fab")
		)
		(fp_line
			(start -0.12065 -0.2794)
			(end 0.12065 -0.2794)
			(stroke
				(width 0.1)
				(type default)
			)
			(layer "F.Fab")
		)
		(fp_line
			(start -0.12065 -0.305054)
			(end -0.12065 -0.2794)
			(stroke
				(width 0.1)
				(type default)
			)
			(layer "F.Fab")
		)
		(fp_line
			(start -0.67945 0.3048)
			(end -0.67945 -0.305054)
			(stroke
				(width 0.1)
				(type default)
			)
			(layer "F.Fab")
		)
		(fp_line
			(start -0.67945 -0.305054)
			(end -0.12065 -0.305054)
			(stroke
				(width 0.1)
				(type default)
			)
			(layer "F.Fab")
		)
		(pad "1" smd circle
			(at -0.40005 0 180)
			(size 0 0)
			(layers "F.Cu" "F.Mask" "F.Paste")
			(net "GPU_BASE_STBY_EN")
		)
		(pad "2" smd circle
			(at 0.40005 0 180)
			(size 0 0)
			(layers "F.Cu" "F.Mask" "F.Paste")
			(net "GND")
		)
	)
	(footprint ""
		(layer "F.Cu")
		(at 411.605222 -416.899344 -90)
		(property "Reference" "C6591"
			(at 0 0 270)
			(layer "F.SilkS")
			(hide yes)
			(effects
				(font
					(size 1.27 1.27)
				)
			)
		)
		(property "Value" ""
			(at 0 0 270)
			(layer "F.Fab")
			(effects
				(font
					(size 1.27 1.27)
				)
			)
		)
		(duplicate_pad_numbers_are_jumpers no)
		(fp_line
			(start -0.299974 0.150114)
			(end -0.299974 -0.150114)
			(stroke
				(width 0.1)
				(type default)
			)
			(layer "F.Fab")
		)
		(fp_line
			(start 0.299974 0.150114)
			(end -0.299974 0.150114)
			(stroke
				(width 0.1)
				(type default)
			)
			(layer "F.Fab")
		)
		(fp_line
			(start -0.299974 -0.150114)
			(end 0.299974 -0.150114)
			(stroke
				(width 0.1)
				(type default)
			)
			(layer "F.Fab")
		)
		(fp_line
			(start 0.299974 -0.150114)
			(end 0.299974 0.150114)
			(stroke
				(width 0.1)
				(type default)
			)
			(layer "F.Fab")
		)
		(pad "1" smd rect
			(at -0.2667 0 270)
			(size 0.3048 0.381)
			(layers "F.Cu" "F.Mask" "F.Paste")
			(net "P5E_CPU0_P2_TX_BUF_C_DP<13>")
		)
		(pad "2" smd rect
			(at 0.2667 0 270)
			(size 0.3048 0.381)
			(layers "F.Cu" "F.Mask" "F.Paste")
			(net "P5E_CPU0_P2_TX_BUF_DP<13>")
		)
	)
	(footprint ""
		(layer "F.Cu")
		(at 297.554142 -400.177)
		(property "Reference" "R997"
			(at 0 0 0)
			(layer "F.SilkS")
			(hide yes)
			(effects
				(font
					(size 1.27 1.27)
				)
			)
		)
		(property "Value" ""
			(at 0 0 0)
			(layer "F.Fab")
			(effects
				(font
					(size 1.27 1.27)
				)
			)
		)
		(duplicate_pad_numbers_are_jumpers no)
		(fp_line
			(start -0.32512 -0.175006)
			(end 0.32512 -0.175006)
			(stroke
				(width 0.1)
				(type default)
			)
			(layer "F.Fab")
		)
		(fp_line
			(start -0.32512 0.175006)
			(end -0.32512 -0.175006)
			(stroke
				(width 0.1)
				(type default)
			)
			(layer "F.Fab")
		)
		(fp_line
			(start 0.32512 -0.175006)
			(end 0.32512 0.175006)
			(stroke
				(width 0.1)
				(type default)
			)
			(layer "F.Fab")
		)
		(fp_line
			(start 0.32512 0.175006)
			(end -0.32512 0.175006)
			(stroke
				(width 0.1)
				(type default)
			)
			(layer "F.Fab")
		)
		(pad "1" smd rect
			(at -0.2667 0)
			(size 0.3048 0.381)
			(layers "F.Cu" "F.Mask" "F.Paste")
			(net "JTAG_TEST_MODE_RT_CPU0_P0")
		)
		(pad "2" smd rect
			(at 0.2667 0 180)
			(size 0.3048 0.381)
			(layers "F.Cu" "F.Mask" "F.Paste")
			(net "GND")
		)
	)
)
